(kicad_pcb
	(version 20260206)
	(generator "pcbnew")
	(generator_version "10.0")
	(general
		(thickness 1.6)
		(legacy_teardrops no)
	)
	(paper "A4")
	(title_block
		(title "v1-chassis-manager — T6M_CM_d_v01_1031_1645.brd")
		(comment 1 "Open CloudServer (Microsoft) / footprints 2483-2491 of 2512")
	)
	(layers
		(0 "F.Cu" signal "TOP")
		(4 "In1.Cu" signal "GND1")
		(6 "In2.Cu" signal "IN1")
		(8 "In3.Cu" signal "VCC1")
		(10 "In4.Cu" signal "VCC2")
		(12 "In5.Cu" signal "GND2")
		(14 "In6.Cu" signal "IN2")
		(16 "In7.Cu" signal "IN3")
		(18 "In8.Cu" signal "GND3")
		(2 "B.Cu" signal "BOTTOM")
		(9 "F.Adhes" user "F.Adhesive")
		(11 "B.Adhes" user "B.Adhesive")
		(13 "F.Paste" user "Package Geometry/Pastemask Top")
		(15 "B.Paste" user "Package Geometry/Pastemask Bottom")
		(5 "F.SilkS" user "Ref Des/Silkscreen Top")
		(7 "B.SilkS" user "Ref Des/Silkscreen Bottom")
		(1 "F.Mask" user "Board Geometry/Soldermask Top")
		(3 "B.Mask" user "Board Geometry/Soldermask Bottom")
		(17 "Dwgs.User" user "User.Drawings")
		(19 "Cmts.User" user "User.Comments")
		(21 "Eco1.User" user "User.Eco1")
		(23 "Eco2.User" user "User.Eco2")
		(25 "Edge.Cuts" user "Board Geometry/Outline")
		(27 "Margin" user)
		(31 "F.CrtYd" user "Package Geometry/Place Bound Top")
		(29 "B.CrtYd" user "Package Geometry/Place Bound Bottom")
		(35 "F.Fab" user "Ref Des/Assembly Top")
		(33 "B.Fab" user "Ref Des/Assembly Bottom")
	)
	(footprint ""
		(layer "B.Cu")
		(at 77.780134 -20.939506 90)
		(property "Reference" "C178"
			(at -4.176014 -0.653542 270)
			(unlocked yes)
			(layer "B.SilkS")
			(effects
				(font
					(size 0.7874 0.5842)
					(thickness 0.1524)
				)
				(justify mirror)
			)
		)
		(property "Value" ""
			(at 0 0 90)
			(layer "B.Fab")
			(effects
				(font
					(size 1.27 1.27)
				)
				(justify mirror)
			)
		)
		(duplicate_pad_numbers_are_jumpers no)
		(fp_line
			(start 1.2954 -0.5842)
			(end -1.2954 -0.5842)
			(stroke
				(width 0.1524)
				(type default)
			)
			(layer "B.SilkS")
		)
		(fp_line
			(start 0 -0.5842)
			(end 0 0.5842)
			(stroke
				(width 0.1524)
				(type default)
			)
			(layer "B.SilkS")
		)
		(fp_line
			(start -1.2954 -0.5842)
			(end -1.2954 0.5842)
			(stroke
				(width 0.1524)
				(type default)
			)
			(layer "B.SilkS")
		)
		(fp_line
			(start 1.2954 0.5842)
			(end 1.2954 -0.5842)
			(stroke
				(width 0.1524)
				(type default)
			)
			(layer "B.SilkS")
		)
		(fp_line
			(start -1.2954 0.5842)
			(end 1.2954 0.5842)
			(stroke
				(width 0.1524)
				(type default)
			)
			(layer "B.SilkS")
		)
		(fp_poly
			(pts
				(xy -0.8636 -0.4572) (xy -0.8636 -0.3556) (xy -1.143 -0.3556) (xy -1.143 0.3556) (xy -0.8636 0.3556)
				(xy -0.8636 0.4572) (xy 0.8636 0.4572) (xy 0.8636 0.3556) (xy 1.143 0.3556) (xy 1.143 -0.3556) (xy 0.8636 -0.3556)
				(xy 0.8636 -0.4572)
			)
			(stroke
				(width 0)
				(type default)
			)
			(fill no)
			(layer "B.CrtYd")
		)
		(fp_line
			(start 0.884936 -0.504952)
			(end -0.884936 -0.504952)
			(stroke
				(width 0.1)
				(type default)
			)
			(layer "B.Fab")
		)
		(fp_line
			(start -0.884936 -0.504952)
			(end -0.884936 0.504952)
			(stroke
				(width 0.1)
				(type default)
			)
			(layer "B.Fab")
		)
		(fp_line
			(start 0.884936 0.504952)
			(end 0.884936 -0.504952)
			(stroke
				(width 0.1)
				(type default)
			)
			(layer "B.Fab")
		)
		(fp_line
			(start -0.884936 0.504952)
			(end 0.884936 0.504952)
			(stroke
				(width 0.1)
				(type default)
			)
			(layer "B.Fab")
		)
		(pad "1" smd rect
			(at -0.7366 0 180)
			(size 0.7112 0.8128)
			(layers "B.Cu" "B.Mask" "B.Paste")
			(net "PV_VDDR_NODE1")
		)
		(pad "2" smd rect
			(at 0.7366 0 180)
			(size 0.7112 0.8128)
			(layers "B.Cu" "B.Mask" "B.Paste")
			(net "GND")
		)
	)
	(footprint ""
		(layer "B.Cu")
		(at 54.736238 -70.502018)
		(property "Reference" "L8"
			(at -14.047978 31.472632 0)
			(unlocked yes)
			(layer "B.SilkS")
			(effects
				(font
					(size 0.7874 0.5842)
					(thickness 0.1524)
				)
				(justify left mirror)
			)
		)
		(property "Value" ""
			(at 0 0 0)
			(layer "B.Fab")
			(effects
				(font
					(size 1.27 1.27)
				)
				(justify mirror)
			)
		)
		(duplicate_pad_numbers_are_jumpers no)
		(fp_line
			(start -0.7874 -0.4064)
			(end -0.7874 0.4064)
			(stroke
				(width 0.1524)
				(type default)
			)
			(layer "B.SilkS")
		)
		(fp_line
			(start -0.7874 0.4064)
			(end 0.7874 0.4064)
			(stroke
				(width 0.1524)
				(type default)
			)
			(layer "B.SilkS")
		)
		(fp_line
			(start -0.0889 0.4064)
			(end -0.0889 -0.4064)
			(stroke
				(width 0.1524)
				(type default)
			)
			(layer "B.SilkS")
		)
		(fp_line
			(start 0.0889 0.4064)
			(end 0.0889 -0.4064)
			(stroke
				(width 0.1524)
				(type default)
			)
			(layer "B.SilkS")
		)
		(fp_line
			(start 0.7874 -0.4064)
			(end -0.7874 -0.4064)
			(stroke
				(width 0.1524)
				(type default)
			)
			(layer "B.SilkS")
		)
		(fp_line
			(start 0.7874 0.4064)
			(end 0.7874 -0.4064)
			(stroke
				(width 0.1524)
				(type default)
			)
			(layer "B.SilkS")
		)
		(fp_poly
			(pts
				(xy 0.5334 0.254) (xy 0.635 0.254) (xy 0.635 0.2286) (xy 0.635 -0.254) (xy 0.5334 -0.254) (xy 0.5334 -0.2794)
				(xy -0.5334 -0.2794) (xy -0.5334 -0.254) (xy -0.635 -0.254) (xy -0.635 0.254) (xy -0.5334 0.254)
				(xy -0.5334 0.2794) (xy 0.508 0.2794) (xy 0.5334 0.2794)
			)
			(stroke
				(width 0)
				(type default)
			)
			(fill no)
			(layer "B.CrtYd")
		)
		(pad "1" smd rect
			(at -0.40005 0 180)
			(size 0.4572 0.508)
			(layers "B.Cu" "B.Mask" "B.Paste")
			(net "P1V5_SUS_NODE1")
		)
		(pad "2" smd rect
			(at 0.40005 0 180)
			(size 0.4572 0.508)
			(layers "B.Cu" "B.Mask" "B.Paste")
			(net "P1V5_SFRPLL_NODE1")
		)
	)
	(footprint ""
		(layer "B.Cu")
		(at 73.12787 -21.11248 90)
		(property "Reference" "C162"
			(at -5.822188 -0.810006 270)
			(unlocked yes)
			(layer "B.SilkS")
			(effects
				(font
					(size 0.7874 0.5842)
					(thickness 0.1524)
				)
				(justify left mirror)
			)
		)
		(property "Value" ""
			(at 0 0 90)
			(layer "B.Fab")
			(effects
				(font
					(size 1.27 1.27)
				)
				(justify mirror)
			)
		)
		(duplicate_pad_numbers_are_jumpers no)
		(fp_line
			(start 0.7874 -0.4064)
			(end -0.7874 -0.4064)
			(stroke
				(width 0.1524)
				(type default)
			)
			(layer "B.SilkS")
		)
		(fp_line
			(start -0.7874 -0.4064)
			(end -0.7874 0.4064)
			(stroke
				(width 0.1524)
				(type default)
			)
			(layer "B.SilkS")
		)
		(fp_line
			(start 0 0.381)
			(end 0 -0.381)
			(stroke
				(width 0.1524)
				(type default)
			)
			(layer "B.SilkS")
		)
		(fp_line
			(start 0.7874 0.4064)
			(end 0.7874 -0.4064)
			(stroke
				(width 0.1524)
				(type default)
			)
			(layer "B.SilkS")
		)
		(fp_line
			(start -0.7874 0.4064)
			(end 0.7874 0.4064)
			(stroke
				(width 0.1524)
				(type default)
			)
			(layer "B.SilkS")
		)
		(fp_poly
			(pts
				(xy 0.5334 0.254) (xy 0.635 0.254) (xy 0.635 0.2286) (xy 0.635 -0.254) (xy 0.5334 -0.254) (xy 0.5334 -0.2794)
				(xy -0.5334 -0.2794) (xy -0.5334 -0.254) (xy -0.635 -0.254) (xy -0.635 0.254) (xy -0.5334 0.254)
				(xy -0.5334 0.2794) (xy 0.508 0.2794) (xy 0.5334 0.2794)
			)
			(stroke
				(width 0)
				(type default)
			)
			(fill no)
			(layer "B.CrtYd")
		)
		(pad "1" smd rect
			(at -0.40005 0 270)
			(size 0.4572 0.508)
			(layers "B.Cu" "B.Mask" "B.Paste")
			(net "PV_VDDR_NODE1")
		)
		(pad "2" smd rect
			(at 0.40005 0 270)
			(size 0.4572 0.508)
			(layers "B.Cu" "B.Mask" "B.Paste")
			(net "GND")
		)
	)
	(footprint ""
		(layer "B.Cu")
		(at 49.38776 -188.126624 -90)
		(property "Reference" "R856"
			(at -4.318254 0.532892 270)
			(unlocked yes)
			(layer "B.SilkS")
			(effects
				(font
					(size 0.7874 0.5842)
					(thickness 0.1524)
				)
				(justify left mirror)
			)
		)
		(property "Value" ""
			(at 0 0 90)
			(layer "B.Fab")
			(effects
				(font
					(size 1.27 1.27)
				)
				(justify mirror)
			)
		)
		(duplicate_pad_numbers_are_jumpers no)
		(fp_line
			(start -0.7874 0.4064)
			(end 0.7874 0.4064)
			(stroke
				(width 0.1524)
				(type default)
			)
			(layer "B.SilkS")
		)
		(fp_line
			(start 0.7874 0.4064)
			(end 0.7874 -0.4064)
			(stroke
				(width 0.1524)
				(type default)
			)
			(layer "B.SilkS")
		)
		(fp_line
			(start -0.7874 -0.4064)
			(end -0.7874 0.4064)
			(stroke
				(width 0.1524)
				(type default)
			)
			(layer "B.SilkS")
		)
		(fp_line
			(start 0.7874 -0.4064)
			(end -0.7874 -0.4064)
			(stroke
				(width 0.1524)
				(type default)
			)
			(layer "B.SilkS")
		)
		(fp_poly
			(pts
				(xy 0.508 0.2794) (xy 0.508 0.2286) (xy 0.635 0.2286) (xy 0.635 -0.254) (xy 0.5334 -0.254) (xy 0.5334 -0.2794)
				(xy -0.5334 -0.2794) (xy -0.5334 -0.254) (xy -0.635 -0.254) (xy -0.635 0.254) (xy -0.5334 0.254)
				(xy -0.5334 0.2794)
			)
			(stroke
				(width 0)
				(type default)
			)
			(fill no)
			(layer "B.CrtYd")
		)
		(pad "1" smd rect
			(at -0.40005 0 90)
			(size 0.4572 0.508)
			(layers "B.Cu" "B.Mask" "B.Paste")
			(net "PSU4_DC_OK_R")
		)
		(pad "2" smd rect
			(at 0.40005 0 90)
			(size 0.4572 0.508)
			(layers "B.Cu" "B.Mask" "B.Paste")
			(net "GND")
		)
	)
	(footprint ""
		(layer "B.Cu")
		(at 171.846494 -122.004836 180)
		(property "Reference" "C785"
			(at 1.347724 3.800348 0)
			(unlocked yes)
			(layer "B.SilkS")
			(effects
				(font
					(size 0.7874 0.5842)
					(thickness 0.1524)
				)
				(justify mirror)
			)
		)
		(property "Value" ""
			(at 0 0 0)
			(layer "B.Fab")
			(effects
				(font
					(size 1.27 1.27)
				)
				(justify mirror)
			)
		)
		(duplicate_pad_numbers_are_jumpers no)
		(fp_line
			(start 1.2954 0.5842)
			(end 1.2954 -0.5842)
			(stroke
				(width 0.1524)
				(type default)
			)
			(layer "B.SilkS")
		)
		(fp_line
			(start 1.2954 -0.5842)
			(end -1.2954 -0.5842)
			(stroke
				(width 0.1524)
				(type default)
			)
			(layer "B.SilkS")
		)
		(fp_line
			(start 0 -0.5842)
			(end 0 0.5842)
			(stroke
				(width 0.1524)
				(type default)
			)
			(layer "B.SilkS")
		)
		(fp_line
			(start -1.2954 0.5842)
			(end 1.2954 0.5842)
			(stroke
				(width 0.1524)
				(type default)
			)
			(layer "B.SilkS")
		)
		(fp_line
			(start -1.2954 -0.5842)
			(end -1.2954 0.5842)
			(stroke
				(width 0.1524)
				(type default)
			)
			(layer "B.SilkS")
		)
		(fp_poly
			(pts
				(xy -0.8636 -0.4572) (xy -0.8636 -0.3556) (xy -1.143 -0.3556) (xy -1.143 0.3556) (xy -0.8636 0.3556)
				(xy -0.8636 0.4572) (xy 0.8636 0.4572) (xy 0.8636 0.3556) (xy 1.143 0.3556) (xy 1.143 -0.3556) (xy 0.8636 -0.3556)
				(xy 0.8636 -0.4572)
			)
			(stroke
				(width 0)
				(type default)
			)
			(fill no)
			(layer "B.CrtYd")
		)
		(fp_line
			(start 0.884936 0.504952)
			(end 0.884936 -0.504952)
			(stroke
				(width 0.1)
				(type default)
			)
			(layer "B.Fab")
		)
		(fp_line
			(start 0.884936 -0.504952)
			(end -0.884936 -0.504952)
			(stroke
				(width 0.1)
				(type default)
			)
			(layer "B.Fab")
		)
		(fp_line
			(start -0.884936 0.504952)
			(end 0.884936 0.504952)
			(stroke
				(width 0.1)
				(type default)
			)
			(layer "B.Fab")
		)
		(fp_line
			(start -0.884936 -0.504952)
			(end -0.884936 0.504952)
			(stroke
				(width 0.1)
				(type default)
			)
			(layer "B.Fab")
		)
		(pad "1" smd rect
			(at -0.7366 0 270)
			(size 0.7112 0.8128)
			(layers "B.Cu" "B.Mask" "B.Paste")
			(net "P3V3_STB_NODE1")
		)
		(pad "2" smd rect
			(at 0.7366 0 270)
			(size 0.7112 0.8128)
			(layers "B.Cu" "B.Mask" "B.Paste")
			(net "GND")
		)
	)
	(footprint ""
		(layer "B.Cu")
		(at 62.027054 -82.117184 -90)
		(property "Reference" "C75"
			(at 30.982666 14.217904 270)
			(unlocked yes)
			(layer "B.SilkS")
			(effects
				(font
					(size 0.7874 0.5842)
					(thickness 0.1524)
				)
				(justify mirror)
			)
		)
		(property "Value" ""
			(at 0 0 90)
			(layer "B.Fab")
			(effects
				(font
					(size 1.27 1.27)
				)
				(justify mirror)
			)
		)
		(duplicate_pad_numbers_are_jumpers no)
		(fp_line
			(start -1.2954 0.5842)
			(end 1.2954 0.5842)
			(stroke
				(width 0.1524)
				(type default)
			)
			(layer "B.SilkS")
		)
		(fp_line
			(start 1.2954 0.5842)
			(end 1.2954 -0.5842)
			(stroke
				(width 0.1524)
				(type default)
			)
			(layer "B.SilkS")
		)
		(fp_line
			(start -1.2954 -0.5842)
			(end -1.2954 0.5842)
			(stroke
				(width 0.1524)
				(type default)
			)
			(layer "B.SilkS")
		)
		(fp_line
			(start 0 -0.5842)
			(end 0 0.5842)
			(stroke
				(width 0.1524)
				(type default)
			)
			(layer "B.SilkS")
		)
		(fp_line
			(start 1.2954 -0.5842)
			(end -1.2954 -0.5842)
			(stroke
				(width 0.1524)
				(type default)
			)
			(layer "B.SilkS")
		)
		(fp_poly
			(pts
				(xy -0.8636 -0.4572) (xy -0.8636 -0.3556) (xy -1.143 -0.3556) (xy -1.143 0.3556) (xy -0.8636 0.3556)
				(xy -0.8636 0.4572) (xy 0.8636 0.4572) (xy 0.8636 0.3556) (xy 1.143 0.3556) (xy 1.143 -0.3556) (xy 0.8636 -0.3556)
				(xy 0.8636 -0.4572)
			)
			(stroke
				(width 0)
				(type default)
			)
			(fill no)
			(layer "B.CrtYd")
		)
		(fp_line
			(start -0.884936 0.504952)
			(end 0.884936 0.504952)
			(stroke
				(width 0.1)
				(type default)
			)
			(layer "B.Fab")
		)
		(fp_line
			(start 0.884936 0.504952)
			(end 0.884936 -0.504952)
			(stroke
				(width 0.1)
				(type default)
			)
			(layer "B.Fab")
		)
		(fp_line
			(start -0.884936 -0.504952)
			(end -0.884936 0.504952)
			(stroke
				(width 0.1)
				(type default)
			)
			(layer "B.Fab")
		)
		(fp_line
			(start 0.884936 -0.504952)
			(end -0.884936 -0.504952)
			(stroke
				(width 0.1)
				(type default)
			)
			(layer "B.Fab")
		)
		(pad "1" smd rect
			(at -0.7366 0)
			(size 0.7112 0.8128)
			(layers "B.Cu" "B.Mask" "B.Paste")
			(net "P1V8_SUS_NODE1")
		)
		(pad "2" smd rect
			(at 0.7366 0)
			(size 0.7112 0.8128)
			(layers "B.Cu" "B.Mask" "B.Paste")
			(net "GND")
		)
	)
	(footprint ""
		(layer "B.Cu")
		(at 37.92474 -147.577302)
		(property "Reference" "R554"
			(at -2.549652 0.339852 0)
			(unlocked yes)
			(layer "B.SilkS")
			(effects
				(font
					(size 0.7874 0.5842)
					(thickness 0.1524)
				)
				(justify left mirror)
			)
		)
		(property "Value" ""
			(at 0 0 0)
			(layer "B.Fab")
			(effects
				(font
					(size 1.27 1.27)
				)
				(justify mirror)
			)
		)
		(duplicate_pad_numbers_are_jumpers no)
		(fp_line
			(start -0.7874 -0.4064)
			(end -0.7874 0.4064)
			(stroke
				(width 0.1524)
				(type default)
			)
			(layer "B.SilkS")
		)
		(fp_line
			(start -0.7874 0.4064)
			(end 0.7874 0.4064)
			(stroke
				(width 0.1524)
				(type default)
			)
			(layer "B.SilkS")
		)
		(fp_line
			(start 0.7874 -0.4064)
			(end -0.7874 -0.4064)
			(stroke
				(width 0.1524)
				(type default)
			)
			(layer "B.SilkS")
		)
		(fp_line
			(start 0.7874 0.4064)
			(end 0.7874 -0.4064)
			(stroke
				(width 0.1524)
				(type default)
			)
			(layer "B.SilkS")
		)
		(fp_poly
			(pts
				(xy 0.508 0.2794) (xy 0.508 0.2286) (xy 0.635 0.2286) (xy 0.635 -0.254) (xy 0.5334 -0.254) (xy 0.5334 -0.2794)
				(xy -0.5334 -0.2794) (xy -0.5334 -0.254) (xy -0.635 -0.254) (xy -0.635 0.254) (xy -0.5334 0.254)
				(xy -0.5334 0.2794)
			)
			(stroke
				(width 0)
				(type default)
			)
			(fill no)
			(layer "B.CrtYd")
		)
		(pad "1" smd rect
			(at -0.40005 0 180)
			(size 0.4572 0.508)
			(layers "B.Cu" "B.Mask" "B.Paste")
			(net "GND")
		)
		(pad "2" smd rect
			(at 0.40005 0 180)
			(size 0.4572 0.508)
			(layers "B.Cu" "B.Mask" "B.Paste")
			(net "LAN1_NC_SI_CLK_IN")
		)
	)
	(footprint ""
		(layer "B.Cu")
		(at 134.985252 -151.31415 90)
		(property "Reference" "C864"
			(at 1.48336 1.756664 270)
			(unlocked yes)
			(layer "B.SilkS")
			(effects
				(font
					(size 0.7874 0.5842)
					(thickness 0.1524)
				)
				(justify left mirror)
			)
		)
		(property "Value" ""
			(at 0 0 90)
			(layer "B.Fab")
			(effects
				(font
					(size 1.27 1.27)
				)
				(justify mirror)
			)
		)
		(duplicate_pad_numbers_are_jumpers no)
		(fp_line
			(start 0.7874 -0.4064)
			(end -0.7874 -0.4064)
			(stroke
				(width 0.1524)
				(type default)
			)
			(layer "B.SilkS")
		)
		(fp_line
			(start -0.7874 -0.4064)
			(end -0.7874 0.4064)
			(stroke
				(width 0.1524)
				(type default)
			)
			(layer "B.SilkS")
		)
		(fp_line
			(start 0 0.381)
			(end 0 -0.381)
			(stroke
				(width 0.1524)
				(type default)
			)
			(layer "B.SilkS")
		)
		(fp_line
			(start 0.7874 0.4064)
			(end 0.7874 -0.4064)
			(stroke
				(width 0.1524)
				(type default)
			)
			(layer "B.SilkS")
		)
		(fp_line
			(start -0.7874 0.4064)
			(end 0.7874 0.4064)
			(stroke
				(width 0.1524)
				(type default)
			)
			(layer "B.SilkS")
		)
		(fp_poly
			(pts
				(xy 0.5334 0.254) (xy 0.635 0.254) (xy 0.635 0.2286) (xy 0.635 -0.254) (xy 0.5334 -0.254) (xy 0.5334 -0.2794)
				(xy -0.5334 -0.2794) (xy -0.5334 -0.254) (xy -0.635 -0.254) (xy -0.635 0.254) (xy -0.5334 0.254)
				(xy -0.5334 0.2794) (xy 0.508 0.2794) (xy 0.5334 0.2794)
			)
			(stroke
				(width 0)
				(type default)
			)
			(fill no)
			(layer "B.CrtYd")
		)
		(pad "1" smd rect
			(at -0.40005 0 270)
			(size 0.4572 0.508)
			(layers "B.Cu" "B.Mask" "B.Paste")
			(net "P1V0_NODE1")
		)
		(pad "2" smd rect
			(at 0.40005 0 270)
			(size 0.4572 0.508)
			(layers "B.Cu" "B.Mask" "B.Paste")
			(net "GND")
		)
	)
	(footprint ""
		(layer "B.Cu")
		(at 144.909032 -34.646616)
		(property "Reference" "R1194"
			(at 1.24714 17.425924 0)
			(unlocked yes)
			(layer "B.SilkS")
			(effects
				(font
					(size 0.7874 0.5842)
					(thickness 0.1524)
				)
				(justify left mirror)
			)
		)
		(property "Value" ""
			(at 0 0 0)
			(layer "B.Fab")
			(effects
				(font
					(size 1.27 1.27)
				)
				(justify mirror)
			)
		)
		(duplicate_pad_numbers_are_jumpers no)
		(fp_line
			(start -0.7874 -0.4064)
			(end -0.7874 0.4064)
			(stroke
				(width 0.1524)
				(type default)
			)
			(layer "B.SilkS")
		)
		(fp_line
			(start -0.7874 0.4064)
			(end 0.7874 0.4064)
			(stroke
				(width 0.1524)
				(type default)
			)
			(layer "B.SilkS")
		)
		(fp_line
			(start 0.7874 -0.4064)
			(end -0.7874 -0.4064)
			(stroke
				(width 0.1524)
				(type default)
			)
			(layer "B.SilkS")
		)
		(fp_line
			(start 0.7874 0.4064)
			(end 0.7874 -0.4064)
			(stroke
				(width 0.1524)
				(type default)
			)
			(layer "B.SilkS")
		)
		(fp_poly
			(pts
				(xy 0.508 0.2794) (xy 0.508 0.2286) (xy 0.635 0.2286) (xy 0.635 -0.254) (xy 0.5334 -0.254) (xy 0.5334 -0.2794)
				(xy -0.5334 -0.2794) (xy -0.5334 -0.254) (xy -0.635 -0.254) (xy -0.635 0.254) (xy -0.5334 0.254)
				(xy -0.5334 0.2794)
			)
			(stroke
				(width 0)
				(type default)
			)
			(fill no)
			(layer "B.CrtYd")
		)
		(pad "1" smd rect
			(at -0.40005 0 180)
			(size 0.4572 0.508)
			(layers "B.Cu" "B.Mask" "B.Paste")
			(net "SIO_CPLD_RSV3_R")
		)
		(pad "2" smd rect
			(at 0.40005 0 180)
			(size 0.4572 0.508)
			(layers "B.Cu" "B.Mask" "B.Paste")
			(net "P3V3_NODE1")
		)
	)
)
